# BASEBOARD_FAB2 (Tioga Pass) — schematic netlist excerpt (pin names and nets, part order shuffled) for the footprints in the layout excerpt that follows; sources: Cadence DE-HDL packaged netlist, KiCad conversion of Wiwynn_Tioga_Pass_MB.brd

C6D8  CAP_A  22.0UF 4V 20% X6S  pkg 0603V  page 42 : A = PVCCMCP_CPU0 ; B = GND
R8B12  RES  0.0 5% CHIP  pkg 0402  page 236 : A = VSENSE_P1V05_PCH_STBY_AVSN ; B = GND
R9G19  RES  0.0 5% CHIP  pkg 0402  page 141 : A = NIC_MDI_SPRV_RJ45_1_DP ; B = NIC_MDI_SPRV_RJ45_1_R_DP

(kicad_pcb
	(version 20260206)
	(generator "pcbnew")
	(generator_version "10.0")
	(general
		(thickness 1.6)
		(legacy_teardrops no)
	)
	(paper "A4")
	(title_block
		(title "Wiwynn_Tioga_Pass_MB.brd")
		(comment 1 "Tioga Pass / footprints 1040-1042 of 4770")
	)
	(layers
		(0 "F.Cu" signal "TOP")
		(4 "In1.Cu" signal "L2GND")
		(6 "In2.Cu" signal "L3")
		(8 "In3.Cu" signal "L4GND")
		(10 "In4.Cu" signal "L5")
		(12 "In5.Cu" signal "L6GND")
		(14 "In6.Cu" signal "L7VCC")
		(16 "In7.Cu" signal "L8VCC")
		(18 "In8.Cu" signal "L9GND")
		(20 "In9.Cu" signal "L10")
		(22 "In10.Cu" signal "L11GND")
		(24 "In11.Cu" signal "L12")
		(26 "In12.Cu" signal "L13GND")
		(2 "B.Cu" signal "BOTTOM")
		(9 "F.Adhes" user "F.Adhesive")
		(11 "B.Adhes" user "B.Adhesive")
		(13 "F.Paste" user "Package Geometry/Pastemask Top")
		(15 "B.Paste" user "Package Geometry/Pastemask Bottom")
		(5 "F.SilkS" user "Ref Des/Silkscreen Top")
		(7 "B.SilkS" user "Ref Des/Silkscreen Bottom")
		(1 "F.Mask" user "Board Geometry/Soldermask Top")
		(3 "B.Mask" user "Board Geometry/Soldermask Bottom")
		(17 "Dwgs.User" user "User.Drawings")
		(19 "Cmts.User" user "User.Comments")
		(21 "Eco1.User" user "User.Eco1")
		(23 "Eco2.User" user "User.Eco2")
		(25 "Edge.Cuts" user "Board Geometry/Outline")
		(27 "Margin" user)
		(31 "F.CrtYd" user "Package Geometry/Place Bound Top")
		(29 "B.CrtYd" user "Package Geometry/Place Bound Bottom")
		(35 "F.Fab" user "Ref Des/Assembly Top")
		(33 "B.Fab" user "Ref Des/Assembly Bottom")
	)
	(footprint ""
		(layer "F.Cu")
		(at 276.978872 -73.318116)
		(property "Reference" "C6D8"
			(at 0 0 0)
			(layer "F.SilkS")
			(hide yes)
			(effects
				(font
					(size 1.27 1.27)
				)
			)
		)
		(property "Value" ""
			(at 0 0 0)
			(layer "F.Fab")
			(effects
				(font
					(size 1.27 1.27)
				)
			)
		)
		(duplicate_pad_numbers_are_jumpers no)
		(fp_poly
			(pts
				(xy -0.4953 -0.2032) (xy 0.4953 -0.2032) (xy 0.4953 1.6002) (xy -0.4953 1.6002)
			)
			(stroke
				(width 0)
				(type default)
			)
			(fill no)
			(layer "F.CrtYd")
		)
		(fp_line
			(start -0.4953 -0.2032)
			(end 0.4953 -0.2032)
			(stroke
				(width 0.1)
				(type default)
			)
			(layer "F.Fab")
		)
		(fp_line
			(start -0.4953 1.6002)
			(end -0.4953 -0.2032)
			(stroke
				(width 0.1)
				(type default)
			)
			(layer "F.Fab")
		)
		(fp_line
			(start 0.4953 -0.2032)
			(end 0.4953 1.6002)
			(stroke
				(width 0.1)
				(type default)
			)
			(layer "F.Fab")
		)
		(fp_line
			(start 0.4953 1.6002)
			(end -0.4953 1.6002)
			(stroke
				(width 0.1)
				(type default)
			)
			(layer "F.Fab")
		)
		(pad "1" smd rect
			(at 0 0)
			(size 0.762 0.889)
			(layers "F.Cu" "F.Mask" "F.Paste")
			(net "PVCCMCP_CPU0")
		)
		(pad "2" smd rect
			(at 0 1.397)
			(size 0.762 0.889)
			(layers "F.Cu" "F.Mask" "F.Paste")
			(net "GND")
		)
		(zone
			(layer "F.Cu")
			(hatch none 0.5)
			(connect_pads
				(clearance 0)
			)
			(min_thickness 0.25)
			(keepout
				(tracks not_allowed)
				(vias allowed)
				(pads allowed)
				(copperpour not_allowed)
				(footprints allowed)
			)
			(placement
				(enabled no)
				(sheetname "")
			)
			(fill
				(thermal_gap 0.5)
				(thermal_bridge_width 0.5)
				(island_removal_mode 0)
			)
			(polygon
				(pts
					(xy 276.597872 -72.873616) (xy 277.359872 -72.873616) (xy 277.359872 -72.365616) (xy 276.597872 -72.365616)
				)
			)
		)
	)
	(footprint ""
		(layer "F.Cu")
		(at 478.545144 -14.478508 -90)
		(property "Reference" "R9G19"
			(at -0.8382 -0.67818 270)
			(unlocked yes)
			(layer "F.SilkS")
			(effects
				(font
					(size 0.4064 0.254)
					(thickness 0.1524)
				)
				(justify left)
			)
		)
		(property "Value" ""
			(at 0 0 270)
			(layer "F.Fab")
			(effects
				(font
					(size 1.27 1.27)
				)
			)
		)
		(duplicate_pad_numbers_are_jumpers no)
		(fp_poly
			(pts
				(xy -0.2794 -0.1016) (xy 0.2794 -0.1016) (xy 0.2794 0.9906) (xy -0.2794 0.9906)
			)
			(stroke
				(width 0)
				(type default)
			)
			(fill no)
			(layer "F.CrtYd")
		)
		(fp_line
			(start -0.2794 0.9906)
			(end 0.2794 0.9906)
			(stroke
				(width 0.1)
				(type default)
			)
			(layer "F.Fab")
		)
		(fp_line
			(start 0.2794 0.9906)
			(end 0.2794 -0.1016)
			(stroke
				(width 0.1)
				(type default)
			)
			(layer "F.Fab")
		)
		(fp_line
			(start -0.2794 -0.1016)
			(end -0.2794 0.9906)
			(stroke
				(width 0.1)
				(type default)
			)
			(layer "F.Fab")
		)
		(fp_line
			(start 0.2794 -0.1016)
			(end -0.2794 -0.1016)
			(stroke
				(width 0.1)
				(type default)
			)
			(layer "F.Fab")
		)
		(pad "1" smd rect
			(at 0 0 270)
			(size 0.508 0.508)
			(layers "F.Cu" "F.Mask" "F.Paste")
			(net "NIC_MDI_SPRV_RJ45_1_DP")
		)
		(pad "2" smd rect
			(at 0 0.889 270)
			(size 0.508 0.508)
			(layers "F.Cu" "F.Mask" "F.Paste")
			(net "NIC_MDI_SPRV_RJ45_1_R_DP")
		)
		(zone
			(layer "F.Cu")
			(hatch none 0.5)
			(connect_pads
				(clearance 0)
			)
			(min_thickness 0.25)
			(keepout
				(tracks not_allowed)
				(vias allowed)
				(pads allowed)
				(copperpour not_allowed)
				(footprints allowed)
			)
			(placement
				(enabled no)
				(sheetname "")
			)
			(fill
				(thermal_gap 0.5)
				(thermal_bridge_width 0.5)
				(island_removal_mode 0)
			)
			(polygon
				(pts
					(xy 477.910144 -14.732508) (xy 477.910144 -14.224508) (xy 478.291144 -14.224508) (xy 478.291144 -14.732508)
				)
			)
		)
		(zone
			(layer "F.Cu")
			(hatch none 0.5)
			(connect_pads
				(clearance 0)
			)
			(min_thickness 0.25)
			(keepout
				(tracks allowed)
				(vias not_allowed)
				(pads allowed)
				(copperpour not_allowed)
				(footprints allowed)
			)
			(placement
				(enabled no)
				(sheetname "")
			)
			(fill
				(thermal_gap 0.5)
				(thermal_bridge_width 0.5)
				(island_removal_mode 0)
			)
			(polygon
				(pts
					(xy 478.291144 -14.732508) (xy 478.291144 -14.224508) (xy 477.910144 -14.224508) (xy 477.910144 -14.732508)
				)
			)
		)
	)
	(footprint ""
		(layer "F.Cu")
		(at 411.327092 -125.088904 -90)
		(property "Reference" "R8B12"
			(at 0 0 270)
			(layer "F.SilkS")
			(hide yes)
			(effects
				(font
					(size 1.27 1.27)
				)
			)
		)
		(property "Value" ""
			(at 0 0 270)
			(layer "F.Fab")
			(effects
				(font
					(size 1.27 1.27)
				)
			)
		)
		(duplicate_pad_numbers_are_jumpers no)
		(fp_poly
			(pts
				(xy -0.2794 -0.1016) (xy 0.2794 -0.1016) (xy 0.2794 0.9906) (xy -0.2794 0.9906)
			)
			(stroke
				(width 0)
				(type default)
			)
			(fill no)
			(layer "F.CrtYd")
		)
		(fp_line
			(start -0.2794 0.9906)
			(end 0.2794 0.9906)
			(stroke
				(width 0.1)
				(type default)
			)
			(layer "F.Fab")
		)
		(fp_line
			(start 0.2794 0.9906)
			(end 0.2794 -0.1016)
			(stroke
				(width 0.1)
				(type default)
			)
			(layer "F.Fab")
		)
		(fp_line
			(start -0.2794 -0.1016)
			(end -0.2794 0.9906)
			(stroke
				(width 0.1)
				(type default)
			)
			(layer "F.Fab")
		)
		(fp_line
			(start 0.2794 -0.1016)
			(end -0.2794 -0.1016)
			(stroke
				(width 0.1)
				(type default)
			)
			(layer "F.Fab")
		)
		(pad "1" smd rect
			(at 0 0 270)
			(size 0.508 0.508)
			(layers "F.Cu" "F.Mask" "F.Paste")
			(net "VSENSE_P1V05_PCH_STBY_AVSN")
		)
		(pad "2" smd rect
			(at 0 0.889 270)
			(size 0.508 0.508)
			(layers "F.Cu" "F.Mask" "F.Paste")
			(net "GND")
		)
		(zone
			(layer "F.Cu")
			(hatch none 0.5)
			(connect_pads
				(clearance 0)
			)
			(min_thickness 0.25)
			(keepout
				(tracks not_allowed)
				(vias allowed)
				(pads allowed)
				(copperpour not_allowed)
				(footprints allowed)
			)
			(placement
				(enabled no)
				(sheetname "")
			)
			(fill
				(thermal_gap 0.5)
				(thermal_bridge_width 0.5)
				(island_removal_mode 0)
			)
			(polygon
				(pts
					(xy 410.692092 -125.342904) (xy 410.692092 -124.834904) (xy 411.073092 -124.834904) (xy 411.073092 -125.342904)
				)
			)
		)
		(zone
			(layer "F.Cu")
			(hatch none 0.5)
			(connect_pads
				(clearance 0)
			)
			(min_thickness 0.25)
			(keepout
				(tracks allowed)
				(vias not_allowed)
				(pads allowed)
				(copperpour not_allowed)
				(footprints allowed)
			)
			(placement
				(enabled no)
				(sheetname "")
			)
			(fill
				(thermal_gap 0.5)
				(thermal_bridge_width 0.5)
				(island_removal_mode 0)
			)
			(polygon
				(pts
					(xy 411.073092 -125.342904) (xy 411.073092 -124.834904) (xy 410.692092 -124.834904) (xy 410.692092 -125.342904)
				)
			)
		)
	)
)
